# BASEBOARD_FAB2 (Tioga Pass) — schematic netlist excerpt (pin names and nets, part order shuffled) for the footprints in the layout excerpt that follows; sources: Cadence DE-HDL packaged netlist, KiCad conversion of Wiwynn_Tioga_Pass_MB.brd

R8G17  RES  0.0 5% CHIP  pkg 0402  page 189 : A = JTAG_BMC_TCK ; B = JTAG_TCK
C5G12  CAP_A  47UF 4V 20% X5R  pkg 0603V  page 217 : A = PVDDQ_ABC ; B = GND
R1D15  RES  100.0K 1% CHIP  pkg 0402  page 199 : A = P12V_PSU ; B = A_HSC_OCP_SEL

(kicad_pcb
	(version 20260206)
	(generator "pcbnew")
	(generator_version "10.0")
	(general
		(thickness 1.6)
		(legacy_teardrops no)
	)
	(paper "A4")
	(title_block
		(title "Wiwynn_Tioga_Pass_MB.brd")
		(comment 1 "Tioga Pass / footprints 1043-1045 of 4770")
	)
	(layers
		(0 "F.Cu" signal "TOP")
		(4 "In1.Cu" signal "L2GND")
		(6 "In2.Cu" signal "L3")
		(8 "In3.Cu" signal "L4GND")
		(10 "In4.Cu" signal "L5")
		(12 "In5.Cu" signal "L6GND")
		(14 "In6.Cu" signal "L7VCC")
		(16 "In7.Cu" signal "L8VCC")
		(18 "In8.Cu" signal "L9GND")
		(20 "In9.Cu" signal "L10")
		(22 "In10.Cu" signal "L11GND")
		(24 "In11.Cu" signal "L12")
		(26 "In12.Cu" signal "L13GND")
		(2 "B.Cu" signal "BOTTOM")
		(9 "F.Adhes" user "F.Adhesive")
		(11 "B.Adhes" user "B.Adhesive")
		(13 "F.Paste" user "Package Geometry/Pastemask Top")
		(15 "B.Paste" user "Package Geometry/Pastemask Bottom")
		(5 "F.SilkS" user "Ref Des/Silkscreen Top")
		(7 "B.SilkS" user "Ref Des/Silkscreen Bottom")
		(1 "F.Mask" user "Board Geometry/Soldermask Top")
		(3 "B.Mask" user "Board Geometry/Soldermask Bottom")
		(17 "Dwgs.User" user "User.Drawings")
		(19 "Cmts.User" user "User.Comments")
		(21 "Eco1.User" user "User.Eco1")
		(23 "Eco2.User" user "User.Eco2")
		(25 "Edge.Cuts" user "Board Geometry/Outline")
		(27 "Margin" user)
		(31 "F.CrtYd" user "Package Geometry/Place Bound Top")
		(29 "B.CrtYd" user "Package Geometry/Place Bound Bottom")
		(35 "F.Fab" user "Ref Des/Assembly Top")
		(33 "B.Fab" user "Ref Des/Assembly Bottom")
	)
	(footprint ""
		(layer "F.Cu")
		(at 395.732 -0.2286)
		(property "Reference" "R8G17"
			(at 0 0 0)
			(layer "F.SilkS")
			(hide yes)
			(effects
				(font
					(size 1.27 1.27)
				)
			)
		)
		(property "Value" ""
			(at 0 0 0)
			(layer "F.Fab")
			(effects
				(font
					(size 1.27 1.27)
				)
			)
		)
		(duplicate_pad_numbers_are_jumpers no)
		(fp_poly
			(pts
				(xy -0.2794 -0.1016) (xy 0.2794 -0.1016) (xy 0.2794 0.9906) (xy -0.2794 0.9906)
			)
			(stroke
				(width 0)
				(type default)
			)
			(fill no)
			(layer "F.CrtYd")
		)
		(fp_line
			(start -0.2794 -0.1016)
			(end -0.2794 0.9906)
			(stroke
				(width 0.1)
				(type default)
			)
			(layer "F.Fab")
		)
		(fp_line
			(start -0.2794 0.9906)
			(end 0.2794 0.9906)
			(stroke
				(width 0.1)
				(type default)
			)
			(layer "F.Fab")
		)
		(fp_line
			(start 0.2794 -0.1016)
			(end -0.2794 -0.1016)
			(stroke
				(width 0.1)
				(type default)
			)
			(layer "F.Fab")
		)
		(fp_line
			(start 0.2794 0.9906)
			(end 0.2794 -0.1016)
			(stroke
				(width 0.1)
				(type default)
			)
			(layer "F.Fab")
		)
		(pad "1" smd rect
			(at 0 0)
			(size 0.508 0.508)
			(layers "F.Cu" "F.Mask" "F.Paste")
			(net "JTAG_BMC_TCK")
		)
		(pad "2" smd rect
			(at 0 0.889)
			(size 0.508 0.508)
			(layers "F.Cu" "F.Mask" "F.Paste")
			(net "JTAG_TCK")
		)
		(zone
			(layer "F.Cu")
			(hatch none 0.5)
			(connect_pads
				(clearance 0)
			)
			(min_thickness 0.25)
			(keepout
				(tracks allowed)
				(vias not_allowed)
				(pads allowed)
				(copperpour not_allowed)
				(footprints allowed)
			)
			(placement
				(enabled no)
				(sheetname "")
			)
			(fill
				(thermal_gap 0.5)
				(thermal_bridge_width 0.5)
				(island_removal_mode 0)
			)
			(polygon
				(pts
					(xy 395.478 0.0254) (xy 395.986 0.0254) (xy 395.986 0.4064) (xy 395.478 0.4064)
				)
			)
		)
		(zone
			(layer "F.Cu")
			(hatch none 0.5)
			(connect_pads
				(clearance 0)
			)
			(min_thickness 0.25)
			(keepout
				(tracks not_allowed)
				(vias allowed)
				(pads allowed)
				(copperpour not_allowed)
				(footprints allowed)
			)
			(placement
				(enabled no)
				(sheetname "")
			)
			(fill
				(thermal_gap 0.5)
				(thermal_bridge_width 0.5)
				(island_removal_mode 0)
			)
			(polygon
				(pts
					(xy 395.478 0.4064) (xy 395.986 0.4064) (xy 395.986 0.0254) (xy 395.478 0.0254)
				)
			)
		)
	)
	(footprint ""
		(layer "F.Cu")
		(at 14.097 -83.058 90)
		(property "Reference" "R1D15"
			(at 0 0 90)
			(layer "F.SilkS")
			(hide yes)
			(effects
				(font
					(size 1.27 1.27)
				)
			)
		)
		(property "Value" ""
			(at 0 0 90)
			(layer "F.Fab")
			(effects
				(font
					(size 1.27 1.27)
				)
			)
		)
		(duplicate_pad_numbers_are_jumpers no)
		(fp_poly
			(pts
				(xy -0.2794 -0.1016) (xy 0.2794 -0.1016) (xy 0.2794 0.9906) (xy -0.2794 0.9906)
			)
			(stroke
				(width 0)
				(type default)
			)
			(fill no)
			(layer "F.CrtYd")
		)
		(fp_line
			(start 0.2794 -0.1016)
			(end -0.2794 -0.1016)
			(stroke
				(width 0.1)
				(type default)
			)
			(layer "F.Fab")
		)
		(fp_line
			(start -0.2794 -0.1016)
			(end -0.2794 0.9906)
			(stroke
				(width 0.1)
				(type default)
			)
			(layer "F.Fab")
		)
		(fp_line
			(start 0.2794 0.9906)
			(end 0.2794 -0.1016)
			(stroke
				(width 0.1)
				(type default)
			)
			(layer "F.Fab")
		)
		(fp_line
			(start -0.2794 0.9906)
			(end 0.2794 0.9906)
			(stroke
				(width 0.1)
				(type default)
			)
			(layer "F.Fab")
		)
		(pad "1" smd rect
			(at 0 0 90)
			(size 0.508 0.508)
			(layers "F.Cu" "F.Mask" "F.Paste")
			(net "P12V_PSU")
		)
		(pad "2" smd rect
			(at 0 0.889 90)
			(size 0.508 0.508)
			(layers "F.Cu" "F.Mask" "F.Paste")
			(net "A_HSC_OCP_SEL")
		)
		(zone
			(layer "F.Cu")
			(hatch none 0.5)
			(connect_pads
				(clearance 0)
			)
			(min_thickness 0.25)
			(keepout
				(tracks allowed)
				(vias not_allowed)
				(pads allowed)
				(copperpour not_allowed)
				(footprints allowed)
			)
			(placement
				(enabled no)
				(sheetname "")
			)
			(fill
				(thermal_gap 0.5)
				(thermal_bridge_width 0.5)
				(island_removal_mode 0)
			)
			(polygon
				(pts
					(xy 14.351 -82.804) (xy 14.351 -83.312) (xy 14.732 -83.312) (xy 14.732 -82.804)
				)
			)
		)
		(zone
			(layer "F.Cu")
			(hatch none 0.5)
			(connect_pads
				(clearance 0)
			)
			(min_thickness 0.25)
			(keepout
				(tracks not_allowed)
				(vias allowed)
				(pads allowed)
				(copperpour not_allowed)
				(footprints allowed)
			)
			(placement
				(enabled no)
				(sheetname "")
			)
			(fill
				(thermal_gap 0.5)
				(thermal_bridge_width 0.5)
				(island_removal_mode 0)
			)
			(polygon
				(pts
					(xy 14.732 -82.804) (xy 14.732 -83.312) (xy 14.351 -83.312) (xy 14.351 -82.804)
				)
			)
		)
	)
	(footprint ""
		(layer "F.Cu")
		(at 248.8565 -3.3528 -90)
		(property "Reference" "C5G12"
			(at 1.848866 0.752348 270)
			(unlocked yes)
			(layer "F.SilkS")
			(effects
				(font
					(size 1.27 0.9652)
					(thickness 0.1524)
				)
			)
		)
		(property "Value" ""
			(at 0 0 270)
			(layer "F.Fab")
			(effects
				(font
					(size 1.27 1.27)
				)
			)
		)
		(duplicate_pad_numbers_are_jumpers no)
		(fp_rect
			(start -0.500126 1.598422)
			(end 0.500126 -0.201422)
			(stroke
				(width 0)
				(type default)
			)
			(fill no)
			(layer "F.CrtYd")
		)
		(fp_line
			(start -0.500126 1.598422)
			(end -0.500126 -0.201422)
			(stroke
				(width 0.1)
				(type default)
			)
			(layer "F.Fab")
		)
		(fp_line
			(start 0.500126 1.598422)
			(end -0.500126 1.598422)
			(stroke
				(width 0.1)
				(type default)
			)
			(layer "F.Fab")
		)
		(fp_line
			(start -0.500126 -0.201422)
			(end 0.500126 -0.201422)
			(stroke
				(width 0.1)
				(type default)
			)
			(layer "F.Fab")
		)
		(fp_line
			(start 0.500126 -0.201422)
			(end 0.500126 1.598422)
			(stroke
				(width 0.1)
				(type default)
			)
			(layer "F.Fab")
		)
		(pad "1" smd rect
			(at 0 0 180)
			(size 0.889 0.9906)
			(layers "F.Cu" "F.Mask" "F.Paste")
			(net "PVDDQ_ABC")
		)
		(pad "2" smd rect
			(at 0 1.397 180)
			(size 0.889 0.9906)
			(layers "F.Cu" "F.Mask" "F.Paste")
			(net "GND")
		)
		(zone
			(layer "F.Cu")
			(hatch none 0.5)
			(connect_pads
				(clearance 0)
			)
			(min_thickness 0.25)
			(keepout
				(tracks not_allowed)
				(vias allowed)
				(pads allowed)
				(copperpour not_allowed)
				(footprints allowed)
			)
			(placement
				(enabled no)
				(sheetname "")
			)
			(fill
				(thermal_gap 0.5)
				(thermal_bridge_width 0.5)
				(island_removal_mode 0)
			)
			(polygon
				(pts
					(xy 247.904 -3.8481) (xy 247.904 -2.8575) (xy 248.412 -2.8575) (xy 248.412 -3.8481)
				)
			)
		)
		(zone
			(layer "F.Cu")
			(hatch none 0.5)
			(connect_pads
				(clearance 0)
			)
			(min_thickness 0.25)
			(keepout
				(tracks allowed)
				(vias not_allowed)
				(pads allowed)
				(copperpour not_allowed)
				(footprints allowed)
			)
			(placement
				(enabled no)
				(sheetname "")
			)
			(fill
				(thermal_gap 0.5)
				(thermal_bridge_width 0.5)
				(island_removal_mode 0)
			)
			(polygon
				(pts
					(xy 247.904 -3.8481) (xy 247.904 -2.8575) (xy 248.412 -2.8575) (xy 248.412 -3.8481)
				)
			)
		)
	)
)
